FILE_TYPE = MULTI_PHYS_TABLE;
PART 'DIODE2A_DUAL'
{========================================================================================}
:VALUE         | PACK_TYPE  | MATERIAL | PART_NUMBER     = ENVCOMP                            | PART_NUMBER  | JEDEC_TYPE | CLASS | DESCRIPTION                                     | HEIGHT     | COMPONENT_TYPE | LEAD_LENGTH | LPID   | SPEED_URL                                                                                                                       | STATUS        | RPL   | AML  | BUS_UNIT | DAYS  ;
{========================================================================================}
'BAS70-05'    | 'SMLF'     | 'DIO'    | 'C90169-001'(!) = 'YES;YES;CNC;CNC;ok;VLD'           | 'C90169-001' | 'SOT23A'   | 'IC'  | 'IC,DS,DIO,SOT-23,BAS70-05,SHTKY'               | '0.044 IN' | 'SMALLSMT'     | ''          | '513'  | 'http://speed.intel.com:8081/speed/module/pdm/item/pdm_item_detail_direct.asp?item_cde=C90169-001&item_rev=01&url_param=unused' | 'Conditional' | 'YES' | '5'  | 'SMO_IC' | '84' 
'BAS70-05'    | 'SMLF'     | 'EMPTY'  | 'C90169-001'(!) = 'YES;YES;CNC;CNC;ok;VLD'           | 'C90169-001' | 'SOT23A'   | 'IO'  | 'IC,DS,DIO,SOT-23,BAS70-05,SHTKY'               | '0.044 IN' | 'SMALLSMT'     | ''          | '513'  | 'http://speed.intel.com:8081/speed/module/pdm/item/pdm_item_detail_direct.asp?item_cde=C90169-001&item_rev=01&url_param=unused' | 'Conditional' | 'YES' | '5'  | 'SMO_IC' | '84' 
END_PART
END.
